(kicad_pcb
	(version 20241229)
	(generator "pcbnew")
	(generator_version "9.0")
	(general
		(thickness 1.62)
		(legacy_teardrops no)
	)
	(paper "A4")
	(title_block
		(title "OCuLink to 10GbE adapter")
		(date "2026-02-23")
		(rev "1.1.0")
		(company "Antmicro Ltd")
		(comment 1 "www.antmicro.com")
		(comment 9 "footprints 6-9 of 510")
	)
	(layers
		(0 "F.Cu" signal)
		(4 "In1.Cu" signal)
		(6 "In2.Cu" signal)
		(8 "In3.Cu" signal)
		(10 "In4.Cu" signal)
		(12 "In5.Cu" signal)
		(14 "In6.Cu" signal)
		(2 "B.Cu" signal)
		(9 "F.Adhes" user "F.Adhesive")
		(11 "B.Adhes" user "B.Adhesive")
		(13 "F.Paste" user)
		(15 "B.Paste" user)
		(5 "F.SilkS" user "F.Silkscreen")
		(7 "B.SilkS" user "B.Silkscreen")
		(1 "F.Mask" user)
		(3 "B.Mask" user)
		(17 "Dwgs.User" user "User.Drawings")
		(19 "Cmts.User" user "User.Comments")
		(21 "Eco1.User" user "User.Eco1")
		(23 "Eco2.User" user "User.Eco2")
		(25 "Edge.Cuts" user)
		(27 "Margin" user)
		(31 "F.CrtYd" user "F.Courtyard")
		(29 "B.CrtYd" user "B.Courtyard")
		(35 "F.Fab" user)
		(33 "B.Fab" user)
	)
	(footprint "antmicro-footprints:C_0402_1005Metric"
		(layer "F.Cu")
		(at 70.693 63.7)
		(descr "Capacitor SMD 0402")
		(tags "capacitor SMD 0402")
		(property "Reference" "C200"
			(at 0.867 0.39 0)
			(layer "F.SilkS")
			(effects
				(font
					(size 0.7 0.7)
					(thickness 0.15)
				)
				(justify left bottom)
			)
		)
		(property "Value" "C_100n_0402"
			(at -1.022927 2.155213 0)
			(layer "F.Fab")
			(hide yes)
			(effects
				(font
					(size 0.7 0.7)
					(thickness 0.15)
				)
				(justify left bottom)
			)
		)
		(property "Datasheet" "https://www.murata.com/products/productdetail?partno=GRM155R61H104KE14%23"
			(at 0 0 0)
			(layer "F.Fab")
			(hide yes)
			(effects
				(font
					(size 1.27 1.27)
					(thickness 0.15)
				)
			)
		)
		(property "Description" "SMD Multilayer Ceramic Capacitor, 0.1 µF, 50 V, 0402 [1005 Metric], ± 10%, X5R, GRM Series"
			(at 0 0 0)
			(layer "F.Fab")
			(hide yes)
			(effects
				(font
					(size 1.27 1.27)
					(thickness 0.15)
				)
			)
		)
		(property "MPN" "GRM155R61H104KE14D"
			(at 0 0 0)
			(unlocked yes)
			(layer "F.Fab")
			(hide yes)
			(effects
				(font
					(size 1 1)
					(thickness 0.15)
				)
			)
		)
		(property "Manufacturer" "Murata"
			(at 0 0 0)
			(unlocked yes)
			(layer "F.Fab")
			(hide yes)
			(effects
				(font
					(size 1 1)
					(thickness 0.15)
				)
			)
		)
		(property "License" "Apache-2.0"
			(at 0 0 0)
			(unlocked yes)
			(layer "F.Fab")
			(hide yes)
			(effects
				(font
					(size 1 1)
					(thickness 0.15)
				)
			)
		)
		(property "Author" "Antmicro"
			(at 0 0 0)
			(unlocked yes)
			(layer "F.Fab")
			(hide yes)
			(effects
				(font
					(size 1 1)
					(thickness 0.15)
				)
			)
		)
		(property "Val" "100n"
			(at 0 0 0)
			(unlocked yes)
			(layer "F.Fab")
			(hide yes)
			(effects
				(font
					(size 1 1)
					(thickness 0.15)
				)
			)
		)
		(property "Voltage" "50V"
			(at 0 0 0)
			(unlocked yes)
			(layer "F.Fab")
			(hide yes)
			(effects
				(font
					(size 1 1)
					(thickness 0.15)
				)
			)
		)
		(property "Dielectric" "X5R"
			(at 0 0 0)
			(unlocked yes)
			(layer "F.Fab")
			(hide yes)
			(effects
				(font
					(size 1 1)
					(thickness 0.15)
				)
			)
		)
		(sheetname "/Power/Ideal diode 1/")
		(sheetfile "ideal-diode.kicad_sch")
		(attr smd)
		(fp_rect
			(start -0.925 -0.47)
			(end 0.925 0.47)
			(stroke
				(width 0.05)
				(type default)
			)
			(fill no)
			(layer "F.CrtYd")
		)
		(fp_line
			(start -0.494 -0.25)
			(end 0.504 -0.25)
			(stroke
				(width 0.15)
				(type solid)
			)
			(layer "F.Fab")
		)
		(fp_line
			(start -0.494 0.248)
			(end -0.494 -0.25)
			(stroke
				(width 0.15)
				(type solid)
			)
			(layer "F.Fab")
		)
		(fp_line
			(start 0.504 -0.25)
			(end 0.504 0.248)
			(stroke
				(width 0.15)
				(type solid)
			)
			(layer "F.Fab")
		)
		(fp_line
			(start 0.504 0.248)
			(end -0.494 0.248)
			(stroke
				(width 0.15)
				(type solid)
			)
			(layer "F.Fab")
		)
		(pad "1" smd roundrect
			(at -0.48 0)
			(size 0.59 0.64)
			(layers "F.Cu" "F.Mask" "F.Paste")
			(roundrect_rratio 0.25)
			(net 28 "GND")
			(pintype "passive")
		)
		(pad "2" smd roundrect
			(at 0.48 0)
			(size 0.59 0.64)
			(layers "F.Cu" "F.Mask" "F.Paste")
			(roundrect_rratio 0.25)
			(net 350 "/Power/+12V_IN")
			(pintype "passive")
		)
	)
	(footprint "antmicro-footprints:C_0402_1005Metric"
		(layer "F.Cu")
		(at 55.1 100.549999 90)
		(descr "Capacitor SMD 0402")
		(tags "capacitor SMD 0402")
		(property "Reference" "C20"
			(at -1.090001 -2.33 90)
			(layer "F.SilkS")
			(effects
				(font
					(size 0.7 0.7)
					(thickness 0.15)
				)
				(justify left bottom)
			)
		)
		(property "Value" "C_33p_0402"
			(at -1.022927 2.155213 90)
			(layer "F.Fab")
			(hide yes)
			(effects
				(font
					(size 0.7 0.7)
					(thickness 0.15)
				)
				(justify left bottom)
			)
		)
		(property "Datasheet" "https://spicat.kyocera-avx.com/product/mlcc/chartview/04025A330FAT2A/"
			(at 0 0 90)
			(layer "F.Fab")
			(hide yes)
			(effects
				(font
					(size 1.27 1.27)
					(thickness 0.15)
				)
			)
		)
		(property "Description" "SMD Multilayer Ceramic Capacitor, 33 pF, 50 V, 0402 [1005 Metric], ± 5%, C0G / NP0, MC"
			(at 0 0 90)
			(layer "F.Fab")
			(hide yes)
			(effects
				(font
					(size 1.27 1.27)
					(thickness 0.15)
				)
			)
		)
		(property "MPN" "04025A330FAT2A"
			(at 0 0 90)
			(unlocked yes)
			(layer "F.Fab")
			(hide yes)
			(effects
				(font
					(size 1 1)
					(thickness 0.15)
				)
			)
		)
		(property "Manufacturer" "KYOCERA AVX"
			(at 0 0 90)
			(unlocked yes)
			(layer "F.Fab")
			(hide yes)
			(effects
				(font
					(size 1 1)
					(thickness 0.15)
				)
			)
		)
		(property "License" "Apache-2.0"
			(at 0 0 90)
			(unlocked yes)
			(layer "F.Fab")
			(hide yes)
			(effects
				(font
					(size 1 1)
					(thickness 0.15)
				)
			)
		)
		(property "Author" "Antmicro"
			(at 0 0 90)
			(unlocked yes)
			(layer "F.Fab")
			(hide yes)
			(effects
				(font
					(size 1 1)
					(thickness 0.15)
				)
			)
		)
		(property "Val" "33p"
			(at 0 0 90)
			(unlocked yes)
			(layer "F.Fab")
			(hide yes)
			(effects
				(font
					(size 1 1)
					(thickness 0.15)
				)
			)
		)
		(property "Voltage" ""
			(at 0 0 90)
			(unlocked yes)
			(layer "F.Fab")
			(hide yes)
			(effects
				(font
					(size 1 1)
					(thickness 0.15)
				)
			)
		)
		(property "Dielectric" ""
			(at 0 0 90)
			(unlocked yes)
			(layer "F.Fab")
			(hide yes)
			(effects
				(font
					(size 1 1)
					(thickness 0.15)
				)
			)
		)
		(sheetname "/Power/")
		(sheetfile "power.kicad_sch")
		(attr smd exclude_from_pos_files exclude_from_bom dnp)
		(fp_rect
			(start -0.925 -0.47)
			(end 0.925 0.47)
			(stroke
				(width 0.05)
				(type default)
			)
			(fill no)
			(layer "F.CrtYd")
		)
		(fp_line
			(start 0.504 -0.25)
			(end 0.504 0.248)
			(stroke
				(width 0.15)
				(type solid)
			)
			(layer "F.Fab")
		)
		(fp_line
			(start -0.494 -0.25)
			(end 0.504 -0.25)
			(stroke
				(width 0.15)
				(type solid)
			)
			(layer "F.Fab")
		)
		(fp_line
			(start 0.504 0.248)
			(end -0.494 0.248)
			(stroke
				(width 0.15)
				(type solid)
			)
			(layer "F.Fab")
		)
		(fp_line
			(start -0.494 0.248)
			(end -0.494 -0.25)
			(stroke
				(width 0.15)
				(type solid)
			)
			(layer "F.Fab")
		)
		(pad "1" smd roundrect
			(at -0.48 0 90)
			(size 0.59 0.64)
			(layers "F.Cu" "F.Mask" "F.Paste")
			(roundrect_rratio 0.25)
			(net 330 "/Power/1V88_FB")
			(pintype "passive")
		)
		(pad "2" smd roundrect
			(at 0.48 0 90)
			(size 0.59 0.64)
			(layers "F.Cu" "F.Mask" "F.Paste")
			(roundrect_rratio 0.25)
			(net 310 "/Power/+1V88_OUT")
			(pintype "passive")
		)
	)
	(footprint "antmicro-footprints:SOT-753"
		(layer "F.Cu")
		(at 81.3 86.35 -90)
		(property "Reference" "U10"
			(at -1 -2.15 90)
			(layer "F.SilkS")
			(effects
				(font
					(size 0.7 0.7)
					(thickness 0.15)
				)
				(justify right top)
			)
		)
		(property "Value" "74LVC1G07_SOT-753"
			(at 0 2.9 90)
			(layer "F.Fab")
			(hide yes)
			(effects
				(font
					(size 0.7 0.7)
					(thickness 0.15)
				)
				(justify right top)
			)
		)
		(property "Datasheet" "https://www.mouser.com/datasheet/2/916/74LVC1G07-1529858.pdf"
			(at 0 0 90)
			(layer "F.Fab")
			(hide yes)
			(effects
				(font
					(size 1.27 1.27)
					(thickness 0.15)
				)
			)
		)
		(property "Description" "Buffer, 74LVC1G07, 1.65 V to 5.5 V, SC-74A-5"
			(at 0 0 90)
			(layer "F.Fab")
			(hide yes)
			(effects
				(font
					(size 1.27 1.27)
					(thickness 0.15)
				)
			)
		)
		(property "MPN" "74LVC1G07GV,125"
			(at 0 0 270)
			(unlocked yes)
			(layer "F.Fab")
			(hide yes)
			(effects
				(font
					(size 1 1)
					(thickness 0.15)
				)
			)
		)
		(property "Manufacturer" "Nexperia"
			(at 0 0 270)
			(unlocked yes)
			(layer "F.Fab")
			(hide yes)
			(effects
				(font
					(size 1 1)
					(thickness 0.15)
				)
			)
		)
		(property "Author" "Antmicro"
			(at 0 0 270)
			(unlocked yes)
			(layer "F.Fab")
			(hide yes)
			(effects
				(font
					(size 1 1)
					(thickness 0.15)
				)
			)
		)
		(property "License" "Apache-2.0"
			(at 0 0 270)
			(unlocked yes)
			(layer "F.Fab")
			(hide yes)
			(effects
				(font
					(size 1 1)
					(thickness 0.15)
				)
			)
		)
		(sheetname "/X710-AT2 Misc/")
		(sheetfile "x710-at2-mics.kicad_sch")
		(attr smd)
		(fp_line
			(start -1.648 1)
			(end -1.648 0.677)
			(stroke
				(width 0.15)
				(type solid)
			)
			(layer "F.SilkS")
		)
		(fp_line
			(start -1.5 1)
			(end -1.648 1)
			(stroke
				(width 0.15)
				(type solid)
			)
			(layer "F.SilkS")
		)
		(fp_line
			(start 1.5 0.998)
			(end 1.648 0.998)
			(stroke
				(width 0.15)
				(type solid)
			)
			(layer "F.SilkS")
		)
		(fp_line
			(start 1.648 0.998)
			(end 1.648 0.699)
			(stroke
				(width 0.15)
				(type solid)
			)
			(layer "F.SilkS")
		)
		(fp_line
			(start -1.651 -1)
			(end -1.651 -0.701)
			(stroke
				(width 0.15)
				(type solid)
			)
			(layer "F.SilkS")
		)
		(fp_line
			(start -1.5 -1)
			(end -1.651 -1)
			(stroke
				(width 0.15)
				(type solid)
			)
			(layer "F.SilkS")
		)
		(fp_line
			(start 1.5 -1)
			(end 1.648 -1)
			(stroke
				(width 0.15)
				(type solid)
			)
			(layer "F.SilkS")
		)
		(fp_line
			(start 1.648 -1)
			(end 1.648 -0.677)
			(stroke
				(width 0.15)
				(type solid)
			)
			(layer "F.SilkS")
		)
		(fp_circle
			(center -1.5 1.35)
			(end -1.46 1.4)
			(stroke
				(width 0.15)
				(type solid)
			)
			(fill yes)
			(layer "F.SilkS")
		)
		(fp_rect
			(start -1.7 -1.901)
			(end 1.699 1.898)
			(stroke
				(width 0.05)
				(type solid)
			)
			(fill no)
			(layer "F.CrtYd")
		)
		(fp_line
			(start -1.351 0.873)
			(end 1.523 0.873)
			(stroke
				(width 0.15)
				(type solid)
			)
			(layer "F.Fab")
		)
		(fp_line
			(start -1.526 0.623)
			(end -1.351 0.873)
			(stroke
				(width 0.15)
				(type solid)
			)
			(layer "F.Fab")
		)
		(fp_line
			(start -1.526 0.623)
			(end -1.526 -0.875)
			(stroke
				(width 0.15)
				(type solid)
			)
			(layer "F.Fab")
		)
		(fp_line
			(start -1.526 -0.875)
			(end 1.523 -0.875)
			(stroke
				(width 0.15)
				(type solid)
			)
			(layer "F.Fab")
		)
		(fp_line
			(start 1.523 -0.875)
			(end 1.523 0.873)
			(stroke
				(width 0.15)
				(type solid)
			)
			(layer "F.Fab")
		)
		(pad "1" smd roundrect
			(at -0.951 1.35 270)
			(size 0.6 1.05)
			(layers "F.Cu" "F.Mask" "F.Paste")
			(roundrect_rratio 0.25)
			(net 401 "unconnected-(U10-NC-Pad1)")
			(pinfunction "NC")
			(pintype "no_connect")
		)
		(pad "2" smd roundrect
			(at 0 1.35 270)
			(size 0.6 1.05)
			(layers "F.Cu" "F.Mask" "F.Paste")
			(roundrect_rratio 0.25)
			(net 396 "Net-(U10-A)")
			(pinfunction "A")
			(pintype "input")
		)
		(pad "3" smd roundrect
			(at 0.949 1.35 270)
			(size 0.6 1.05)
			(layers "F.Cu" "F.Mask" "F.Paste")
			(roundrect_rratio 0.25)
			(net 28 "GND")
			(pinfunction "GND")
			(pintype "power_in")
		)
		(pad "4" smd roundrect
			(at 0.949 -1.351 270)
			(size 0.6 1.05)
			(layers "F.Cu" "F.Mask" "F.Paste")
			(roundrect_rratio 0.25)
			(net 99 "/X710-AT2 Misc/LAN_PWR_GOOD")
			(pinfunction "Y")
			(pintype "output")
		)
		(pad "5" smd roundrect
			(at -0.951 -1.351 270)
			(size 0.6 1.05)
			(layers "F.Cu" "F.Mask" "F.Paste")
			(roundrect_rratio 0.25)
			(net 78 "Net-(U10-VCC)")
			(pinfunction "VCC")
			(pintype "power_in")
		)
	)
	(footprint "antmicro-footprints:C_0603_1608Metric_EIA"
		(layer "F.Cu")
		(at 53.25 103.900001 -90)
		(descr "Capacitor SMD 0603, IPC-7351 Density Level A")
		(tags "Capacitor 0603")
		(property "Reference" "C22"
			(at 1.219999 1.72 270)
			(layer "F.SilkS")
			(effects
				(font
					(size 0.7 0.7)
					(thickness 0.15)
				)
				(justify right top)
			)
		)
		(property "Value" "C_22u_16V_0603"
			(at -1.42757 1.770288 90)
			(layer "F.Fab")
			(hide yes)
			(effects
				(font
					(size 0.7 0.7)
					(thickness 0.15)
				)
				(justify right top)
			)
		)
		(property "Datasheet" "https://product.samsungsem.com/mlcc/CL10A226MO7JZN.do"
			(at 0 0 90)
			(layer "F.Fab")
			(hide yes)
			(effects
				(font
					(size 1.27 1.27)
					(thickness 0.15)
				)
			)
		)
		(property "Description" "SMD Multilayer Ceramic Capacitor"
			(at 0 0 90)
			(layer "F.Fab")
			(hide yes)
			(effects
				(font
					(size 1.27 1.27)
					(thickness 0.15)
				)
			)
		)
		(property "MPN" "CL10A226MO7JZNC"
			(at 0 0 270)
			(unlocked yes)
			(layer "F.Fab")
			(hide yes)
			(effects
				(font
					(size 1 1)
					(thickness 0.15)
				)
			)
		)
		(property "Manufacturer" "Samsung Electro-Mechanics"
			(at 0 0 270)
			(unlocked yes)
			(layer "F.Fab")
			(hide yes)
			(effects
				(font
					(size 1 1)
					(thickness 0.15)
				)
			)
		)
		(property "License" "Apache-2.0"
			(at 0 0 270)
			(unlocked yes)
			(layer "F.Fab")
			(hide yes)
			(effects
				(font
					(size 1 1)
					(thickness 0.15)
				)
			)
		)
		(property "Author" "Antmicro"
			(at 0 0 270)
			(unlocked yes)
			(layer "F.Fab")
			(hide yes)
			(effects
				(font
					(size 1 1)
					(thickness 0.15)
				)
			)
		)
		(property "Val" "22u"
			(at 0 0 270)
			(unlocked yes)
			(layer "F.Fab")
			(hide yes)
			(effects
				(font
					(size 1 1)
					(thickness 0.15)
				)
			)
		)
		(property "Voltage" "16V"
			(at 0 0 270)
			(unlocked yes)
			(layer "F.Fab")
			(hide yes)
			(effects
				(font
					(size 1 1)
					(thickness 0.15)
				)
			)
		)
		(property "Dielectric" ""
			(at 0 0 270)
			(unlocked yes)
			(layer "F.Fab")
			(hide yes)
			(effects
				(font
					(size 1 1)
					(thickness 0.15)
				)
			)
		)
		(property "Public" "False"
			(at 0 0 270)
			(unlocked yes)
			(layer "F.Fab")
			(hide yes)
			(effects
				(font
					(size 1 1)
					(thickness 0.15)
				)
			)
		)
		(sheetname "/Power/")
		(sheetfile "power.kicad_sch")
		(attr smd)
		(fp_line
			(start -0.15 0.55)
			(end 0.15 0.55)
			(stroke
				(width 0.15)
				(type solid)
			)
			(layer "F.SilkS")
		)
		(fp_line
			(start -0.15 -0.55)
			(end 0.15 -0.55)
			(stroke
				(width 0.15)
				(type solid)
			)
			(layer "F.SilkS")
		)
		(fp_rect
			(start -1.25 -0.65)
			(end 1.25 0.65)
			(stroke
				(width 0.05)
				(type solid)
			)
			(fill no)
			(layer "F.CrtYd")
		)
		(fp_rect
			(start -0.8 -0.45)
			(end 0.8 0.45)
			(stroke
				(width 0.15)
				(type solid)
			)
			(fill no)
			(layer "F.Fab")
		)
		(pad "1" smd roundrect
			(at -0.7 0 270)
			(size 0.8 1.1)
			(layers "F.Cu" "F.Mask" "F.Paste")
			(roundrect_rratio 0.2)
			(net 28 "GND")
			(pintype "passive")
		)
		(pad "2" smd roundrect
			(at 0.7 0 270)
			(size 0.8 1.1)
			(layers "F.Cu" "F.Mask" "F.Paste")
			(roundrect_rratio 0.2)
			(net 314 "VCC")
			(pintype "passive")
		)
	)
)
